# T6G (Grand Teton) — schematic netlist excerpt (pin names and nets, part order shuffled) for the footprints in the layout excerpt that follows; sources: Cadence DE-HDL packaged netlist, KiCad conversion of 04192023_DAF0TMB3IC0_F0TG_MB_C_brd_V02_OCP.brd

R98  Q_RES  1K 1% EMPTY  pkg 0402LF  page 94 : A = P3V3 ; B = PWRGD_CHI_CPU0_DIMM
C2600  Q_CAP  22UF 4V 20% X6S  pkg C0402  page 70 : A = PVDD11_S3_P0 ; B = GND

(kicad_pcb
	(version 20260206)
	(generator "pcbnew")
	(generator_version "10.0")
	(general
		(thickness 1.6)
		(legacy_teardrops no)
	)
	(paper "A4")
	(title_block
		(title "04192023_DAF0TMB3IC0_F0TG_MB_C_brd_V02_OCP.brd")
		(comment 1 "Grand Teton / footprints 7477-7478 of 8354")
	)
	(layers
		(0 "F.Cu" signal "TOP")
		(4 "In1.Cu" signal "GND")
		(6 "In2.Cu" signal "IN1")
		(8 "In3.Cu" signal "GND1")
		(10 "In4.Cu" signal "IN2")
		(12 "In5.Cu" signal "GND2")
		(14 "In6.Cu" signal "IN3")
		(16 "In7.Cu" signal "GND3")
		(18 "In8.Cu" signal "VCC")
		(20 "In9.Cu" signal "VCC1")
		(22 "In10.Cu" signal "GND4")
		(24 "In11.Cu" signal "IN4")
		(26 "In12.Cu" signal "GND5")
		(28 "In13.Cu" signal "IN5")
		(30 "In14.Cu" signal "GND6")
		(32 "In15.Cu" signal "IN6")
		(34 "In16.Cu" signal "GND7")
		(2 "B.Cu" signal "BOTTOM")
		(9 "F.Adhes" user "F.Adhesive")
		(11 "B.Adhes" user "B.Adhesive")
		(13 "F.Paste" user "Package Geometry/Pastemask Top")
		(15 "B.Paste" user "Package Geometry/Pastemask Bottom")
		(5 "F.SilkS" user "Ref Des/Silkscreen Top")
		(7 "B.SilkS" user "Ref Des/Silkscreen Bottom")
		(1 "F.Mask" user "Board Geometry/Soldermask Top")
		(3 "B.Mask" user "Board Geometry/Soldermask Bottom")
		(17 "Dwgs.User" user "User.Drawings")
		(19 "Cmts.User" user "User.Comments")
		(21 "Eco1.User" user "User.Eco1")
		(23 "Eco2.User" user "User.Eco2")
		(25 "Edge.Cuts" user "Board Geometry/Outline")
		(27 "Margin" user)
		(31 "F.CrtYd" user "Package Geometry/Place Bound Top")
		(29 "B.CrtYd" user "Package Geometry/Place Bound Bottom")
		(35 "F.Fab" user "Ref Des/Assembly Top")
		(33 "B.Fab" user "Ref Des/Assembly Bottom")
	)
	(footprint ""
		(layer "B.Cu")
		(at 428.211742 -193.99631)
		(property "Reference" "R98"
			(at 0 0 0)
			(layer "B.SilkS")
			(hide yes)
			(effects
				(font
					(size 1.27 1.27)
				)
				(justify mirror)
			)
		)
		(property "Value" ""
			(at 0 0 0)
			(layer "B.Fab")
			(effects
				(font
					(size 1.27 1.27)
				)
				(justify mirror)
			)
		)
		(duplicate_pad_numbers_are_jumpers no)
		(fp_line
			(start -0.7874 -0.4064)
			(end -0.7874 0.4064)
			(stroke
				(width 0.1524)
				(type default)
			)
			(layer "B.SilkS")
		)
		(fp_line
			(start -0.7874 0.4064)
			(end 0.7874 0.4064)
			(stroke
				(width 0.1524)
				(type default)
			)
			(layer "B.SilkS")
		)
		(fp_line
			(start 0.7874 -0.4064)
			(end -0.7874 -0.4064)
			(stroke
				(width 0.1524)
				(type default)
			)
			(layer "B.SilkS")
		)
		(fp_line
			(start 0.7874 0.4064)
			(end 0.7874 -0.4064)
			(stroke
				(width 0.1524)
				(type default)
			)
			(layer "B.SilkS")
		)
		(fp_line
			(start -0.67945 -0.3048)
			(end -0.67945 0.3048)
			(stroke
				(width 0.1)
				(type default)
			)
			(layer "B.Fab")
		)
		(fp_line
			(start -0.67945 0.3048)
			(end -0.120396 0.3048)
			(stroke
				(width 0.1)
				(type default)
			)
			(layer "B.Fab")
		)
		(fp_line
			(start -0.12065 -0.3048)
			(end -0.67945 -0.3048)
			(stroke
				(width 0.1)
				(type default)
			)
			(layer "B.Fab")
		)
		(fp_line
			(start -0.12065 -0.2794)
			(end -0.12065 -0.3048)
			(stroke
				(width 0.1)
				(type default)
			)
			(layer "B.Fab")
		)
		(fp_line
			(start -0.120396 0.2794)
			(end 0.12065 0.2794)
			(stroke
				(width 0.1)
				(type default)
			)
			(layer "B.Fab")
		)
		(fp_line
			(start -0.120396 0.3048)
			(end -0.120396 0.2794)
			(stroke
				(width 0.1)
				(type default)
			)
			(layer "B.Fab")
		)
		(fp_line
			(start 0.12065 -0.305054)
			(end 0.12065 -0.2794)
			(stroke
				(width 0.1)
				(type default)
			)
			(layer "B.Fab")
		)
		(fp_line
			(start 0.12065 -0.2794)
			(end -0.12065 -0.2794)
			(stroke
				(width 0.1)
				(type default)
			)
			(layer "B.Fab")
		)
		(fp_line
			(start 0.12065 0.2794)
			(end 0.12065 0.3048)
			(stroke
				(width 0.1)
				(type default)
			)
			(layer "B.Fab")
		)
		(fp_line
			(start 0.12065 0.3048)
			(end 0.67945 0.3048)
			(stroke
				(width 0.1)
				(type default)
			)
			(layer "B.Fab")
		)
		(fp_line
			(start 0.67945 -0.305054)
			(end 0.12065 -0.305054)
			(stroke
				(width 0.1)
				(type default)
			)
			(layer "B.Fab")
		)
		(fp_line
			(start 0.67945 0.3048)
			(end 0.67945 -0.305054)
			(stroke
				(width 0.1)
				(type default)
			)
			(layer "B.Fab")
		)
		(pad "1" smd circle
			(at 0.40005 0 180)
			(size 0 0)
			(layers "B.Cu" "B.Mask" "B.Paste")
			(net "P3V3")
		)
		(pad "2" smd circle
			(at -0.40005 0 180)
			(size 0 0)
			(layers "B.Cu" "B.Mask" "B.Paste")
			(net "PWRGD_CHI_CPU0_DIMM")
		)
	)
	(footprint ""
		(layer "B.Cu")
		(at 369.519454 -266.00531)
		(property "Reference" "C2600"
			(at 0 0 0)
			(layer "B.SilkS")
			(hide yes)
			(effects
				(font
					(size 1.27 1.27)
				)
				(justify mirror)
			)
		)
		(property "Value" ""
			(at 0 0 0)
			(layer "B.Fab")
			(effects
				(font
					(size 1.27 1.27)
				)
				(justify mirror)
			)
		)
		(duplicate_pad_numbers_are_jumpers no)
		(fp_line
			(start -0.7874 -0.4064)
			(end -0.7874 0.4064)
			(stroke
				(width 0.1524)
				(type default)
			)
			(layer "B.SilkS")
		)
		(fp_line
			(start -0.7874 0.4064)
			(end 0.7874 0.4064)
			(stroke
				(width 0.1524)
				(type default)
			)
			(layer "B.SilkS")
		)
		(fp_line
			(start 0.7874 -0.4064)
			(end -0.7874 -0.4064)
			(stroke
				(width 0.1524)
				(type default)
			)
			(layer "B.SilkS")
		)
		(fp_line
			(start 0.7874 0.4064)
			(end 0.7874 -0.4064)
			(stroke
				(width 0.1524)
				(type default)
			)
			(layer "B.SilkS")
		)
		(fp_line
			(start -0.67945 -0.3048)
			(end -0.67945 0.3048)
			(stroke
				(width 0.1)
				(type default)
			)
			(layer "B.Fab")
		)
		(fp_line
			(start -0.67945 0.3048)
			(end -0.120396 0.3048)
			(stroke
				(width 0.1)
				(type default)
			)
			(layer "B.Fab")
		)
		(fp_line
			(start -0.12065 -0.3048)
			(end -0.67945 -0.3048)
			(stroke
				(width 0.1)
				(type default)
			)
			(layer "B.Fab")
		)
		(fp_line
			(start -0.12065 -0.2794)
			(end -0.12065 -0.3048)
			(stroke
				(width 0.1)
				(type default)
			)
			(layer "B.Fab")
		)
		(fp_line
			(start -0.120396 0.2794)
			(end 0.12065 0.2794)
			(stroke
				(width 0.1)
				(type default)
			)
			(layer "B.Fab")
		)
		(fp_line
			(start -0.120396 0.3048)
			(end -0.120396 0.2794)
			(stroke
				(width 0.1)
				(type default)
			)
			(layer "B.Fab")
		)
		(fp_line
			(start 0.12065 -0.305054)
			(end 0.12065 -0.2794)
			(stroke
				(width 0.1)
				(type default)
			)
			(layer "B.Fab")
		)
		(fp_line
			(start 0.12065 -0.2794)
			(end -0.12065 -0.2794)
			(stroke
				(width 0.1)
				(type default)
			)
			(layer "B.Fab")
		)
		(fp_line
			(start 0.12065 0.2794)
			(end 0.12065 0.3048)
			(stroke
				(width 0.1)
				(type default)
			)
			(layer "B.Fab")
		)
		(fp_line
			(start 0.12065 0.3048)
			(end 0.67945 0.3048)
			(stroke
				(width 0.1)
				(type default)
			)
			(layer "B.Fab")
		)
		(fp_line
			(start 0.67945 -0.305054)
			(end 0.12065 -0.305054)
			(stroke
				(width 0.1)
				(type default)
			)
			(layer "B.Fab")
		)
		(fp_line
			(start 0.67945 0.3048)
			(end 0.67945 -0.305054)
			(stroke
				(width 0.1)
				(type default)
			)
			(layer "B.Fab")
		)
		(pad "1" smd circle
			(at 0.40005 0 180)
			(size 0 0)
			(layers "B.Cu" "B.Mask" "B.Paste")
			(net "PVDD11_S3_P0")
		)
		(pad "2" smd circle
			(at -0.40005 0 180)
			(size 0 0)
			(layers "B.Cu" "B.Mask" "B.Paste")
			(net "GND")
		)
	)
)
